# BASEBOARD_FAB2 (Tioga Pass) — schematic parts with pin connectivity, parts 4662–4665 of 4751; source: Cadence DE-HDL packaged netlist (pstxprt.dat, pstxnet.dat, pstchip.dat)

U4C2  GTL2014  IC  pkg SM  page 96
  1  DIR  IN  = PU_GTL2014_2_DIR
  2  B0  BI  = PWRGD_CPU1_DRAMPWROK_KLM_G
  3  B1  BI  = PWRGD_CPU1_DRAMPWROK_GHJ_G
  4  VREF  POWER  = PD_GTL2014_2_VREF
  5  B2  BI  = RST_CPU1_G_N
  6  B3  BI  = PWRGD_CPU1_G
  7  GND(0)  GROUND  = GND
  8  GND(1)  GROUND  = GND
  9  A3  BI  = PWRGD_CPU1_LVC3
  10  A2  BI  = RST_CPU1_LVC3_N
  11  GND(2)  GROUND  = GND
  12  A1  BI  = PWRGD_DRAMPWRGD
  13  A0  BI  = PWRGD_DRAMPWRGD
  14  VCC  POWER  = P3V3_STBY

U4G1  PCA9617  IC  pkg SSOP  page 99
  1  VCCA  POWER  = PVCCIO_CPU1
  2  SCLA  IN  = SMB_DDR_GHJ_SCL_G
  3  SDAA  IN  = SMB_DDR_GHJ_SDA_G
  5  EN  IN  = TP_SMB_DDR_GHJ_EN
  6  SDAB  OUT  = SMB_DDR_GHJ_VPP_SDA_R
  7  SCLB  OUT  = SMB_DDR_GHJ_VPP_SCL_R
  8  VCCB  POWER  = PVPP_GHJ

U4R1  74CBTLV1G125  IC  pkg SMLF  page 113
  1  OE_N  IN  = FM_CPU0_PKGID1
  2  A  IN  = P1V8_MCP_CPU0
  4  B  OUT  = JTAG_MCP_CPU0_TDI_R

U5D1  SKX_EXT_B  IC  pkg BGA1  page 21  (pins 1-339 of 3647)
  A4  RSVD(304)  BI  = TP_CPU0_RSVD_304
  A6  RSVD(303)  BI  = TP_CPU0_RSVD_303
  A8  CD_VPP(3)  POWER  = PVPP_ABC
  A10  CD_VPP(2)  POWER  = PVPP_ABC
  A12  CD_VPP(1)  POWER  = PVPP_ABC
  A14  RSVD(302)  BI  = P1V8_MCP_CPU0
  A16  RSVD(301)  BI  = P1V8_MCP_CPU0
  A24  RSVD(300)  BI  = TP_CPU0_RSVD_300
  A26  VSS(1185)  GROUND  = GND
  A28  DDR1_DQS_DN(15)  BI  = M_B_DQS_DN<15>
  A30  VSS(1184)  GROUND  = GND
  A32  VSS(1183)  GROUND  = GND
  A34  DDR1_DQS_DN(14)  BI  = M_B_DQS_DN<14>
  A36  VSS(1182)  GROUND  = GND
  A38  VSS(1181)  GROUND  = GND
  A40  DDR0_DQS_DN(13)  BI  = M_A_DQS_DN<13>
  A42  VSS(1252)  GROUND  = GND
  AA2  UPI0_TX_DP(4)  OUT  = UPI_CPU0_CPU1_P0P0_DP<15>
  AA4  VSS(935)  GROUND  = GND
  AA6  UPI0_RX_DP(2)  IN  = UPI_CPU1_CPU0_P0P0_DP<17>
  AA8  UPI0_RX_DN(1)  IN  = UPI_CPU1_CPU0_P0P0_DN<18>
  AA10  VCCIO(45)  POWER  = PVCCIO_CPU0
  AA12  BPM_N(4)  BI  = TP_XDP_CPU0_OBSDATA_A2_MBP4_N
  AA14  TCK  IN  = XDP_CPU_TCK0
  AA16  VSS(934)  GROUND  = GND
  AA18  VSS(933)  GROUND  = GND
  AA20  UPI1_RX_DP(19)  IN  = UPI_CPU1_CPU0_P1P1_DP<0>
  AA22  VSS(932)  GROUND  = GND
  AA24  VSS(931)  GROUND  = GND
  AA26  DDR1_DQ(63)  BI  = M_B_DQ<63>
  AA28  DDR1_DQ(57)  BI  = M_B_DQ<57>
  AA30  VSS(930)  GROUND  = GND
  AA32  DDR2_DQ(47)  BI  = M_C_DQ<47>
  AA34  DDR2_DQ(41)  BI  = M_C_DQ<41>
  AA36  VSS(929)  GROUND  = GND
  AA38  DDR2_DQ(39)  BI  = M_C_DQ<39>
  AA40  DDR2_DQ(33)  BI  = M_C_DQ<33>
  AA42  VSS(928)  GROUND  = GND
  AA46  DDR2_CS_N(3)  OUT  = M_C_CS_N<3>
  AA48  DDR2_ODT(1)  OUT  = M_C_ODT<1>
  AA50  DDR2_ODT(0)  OUT  = M_C_ODT<0>
  AA52  DDR2_MA(16)  OUT  = M_C_MA<16>
  AA54  DDR2_CLK_DN(0)  OUT  = M_C_CLK_DN<0>
  AA56  DDR2_CLK_DN(2)  OUT  = M_C_CLK_DN<2>
  AA58  DDR2_MA(4)  OUT  = M_C_MA<4>
  AA60  DDR2_BG(0)  OUT  = M_C_BG<0>
  AA62  DDR2_CKE(0)  OUT  = M_C_CKE<0>
  AA64  VSS(927)  GROUND  = GND
  AA66  VSS(926)  GROUND  = GND
  AA68  VSS(925)  GROUND  = GND
  AA70  DDR2_DQ(17)  BI  = M_C_DQ<17>
  AA72  DDR2_DQ(20)  BI  = M_C_DQ<20>
  AA74  DDR2_DQS_DN(1)  BI  = M_C_DQS_DN<1>
  AA76  VSS(924)  GROUND  = GND
  AA78  VSS(923)  GROUND  = GND
  AA80  VSS(922)  GROUND  = GND
  AA82  VSS(921)  GROUND  = GND
  AA84  DDR0_DQ(13)  BI  = M_A_DQ<13>
  AA86  DDR0_DQ(12)  BI  = M_A_DQ<12>
  AB1  VSS(920)  GROUND  = GND
  AB3  UPI0_TX_DN(4)  OUT  = UPI_CPU0_CPU1_P0P0_DN<15>
  AB5  VSS(919)  GROUND  = GND
  AB7  UPI0_RX_DN(2)  IN  = UPI_CPU1_CPU0_P0P0_DN<17>
  AB9  UPI0_RX_DP(0)  IN  = UPI_CPU1_CPU0_P0P0_DP<19>
  AB11  VSS(918)  GROUND  = GND
  AB13  SKTOCC_N  OUT  = FM_CPU0_SKTOCC_LVT3_N
  AB15  THERMTRIP_N  OUT  = H_CPU0_THERMTRIP_G_N
  AB17  PROCDIS_N  IN  = TP_CPU0_PROCDIS_G_N
  AB19  UPI1_RX_DN(19)  IN  = UPI_CPU1_CPU0_P1P1_DN<0>
  AB21  VSS(917)  GROUND  = GND
  AB23  VSS(916)  GROUND  = GND
  AB25  VSS(915)  GROUND  = GND
  AB27  DDR1_DQS_DN(7)  BI  = M_B_DQS_DN<7>
  AB29  VSS(914)  GROUND  = GND
  AB31  VSS(913)  GROUND  = GND
  AB33  DDR2_DQS_DN(5)  BI  = M_C_DQS_DN<5>
  AB35  VSS(912)  GROUND  = GND
  AB37  VSS(911)  GROUND  = GND
  AB39  DDR2_DQS_DN(4)  BI  = M_C_DQS_DN<4>
  AB41  VSS(910)  GROUND  = GND
  AB43  DDR012_RCOMP(1)  BI  = A_CPU0_ABC_RCOMP1
  AB45  DDR2_CID(2)  OUT  = M_C_C<2>
  AB47  DDR2_ODT(3)  OUT  = M_C_ODT<3>
  AB49  DDR2_CS_N(1)  OUT  = M_C_CS_N<1>
  AB51  DDR2_CS_N(4)  OUT  = M_C_CS_N<4>
  AB53  DDR2_MA(0)  OUT  = M_C_MA<0>
  AB55  DDR2_CLK_DP(0)  OUT  = M_C_CLK_DP<0>
  AB57  DDR2_CLK_DP(2)  OUT  = M_C_CLK_DP<2>
  AB59  DDR2_MA(6)  OUT  = M_C_MA<6>
  AB61  DDR2_ACT_N  OUT  = M_C_ACT_N
  AB63  DDR2_CKE(3)  OUT  = M_C_CKE<3>
  AB65  VSS(909)  GROUND  = GND
  AB67  DDR0_DQS_DN(17)  BI  = M_A_DQS_DN<17>
  AB69  VSS(908)  GROUND  = GND
  AB71  DDR2_DQ(21)  BI  = M_C_DQ<21>
  AB73  VSS(907)  GROUND  = GND
  AB75  DDR2_DQS_DP(1)  BI  = M_C_DQS_DP<1>
  AB77  DDR2_DQ(14)  BI  = M_C_DQ<14>
  AB79  VSS(906)  GROUND  = GND
  AB81  DDR1_DQ(11)  BI  = M_B_DQ<11>
  AB83  VSS(905)  GROUND  = GND
  AB85  VSS(904)  GROUND  = GND
  AC2  UPI0_TX_DN(5)  OUT  = UPI_CPU0_CPU1_P0P0_DN<14>
  AC4  VCCIO(43)  POWER  = PVCCIO_CPU0
  AC6  UPI0_RX_DP(3)  IN  = UPI_CPU1_CPU0_P0P0_DP<16>
  AC8  UPI0_RX_DP(1)  IN  = UPI_CPU1_CPU0_P0P0_DP<18>
  AC10  UPI0_RX_DN(0)  IN  = UPI_CPU1_CPU0_P0P0_DN<19>
  AC12  BPM_N(7)  BI  = XDP_CPU_OBSFN_B1_MBP7_N
  AC14  TDI  IN  = XDP_CPU_TDI
  AC16  PROCHOT_N  BI  = H_CPU0_PROCHOT_G_N
  AC18  VSS(903)  GROUND  = GND
  AC20  VCCIO(44)  POWER  = PVCCIO_CPU0
  AC22  VSS(902)  GROUND  = GND
  AC24  DDR2_DQS_DN(16)  BI  = M_C_DQS_DN<16>
  AC26  VSS(901)  GROUND  = GND
  AC28  VSS(900)  GROUND  = GND
  AC30  DDR2_DQS_DN(15)  BI  = M_C_DQS_DN<15>
  AC32  VSS(899)  GROUND  = GND
  AC34  VSS(898)  GROUND  = GND
  AC36  VCCIO(97)  POWER  = PVCCIO_CPU0
  AC38  VSS(897)  GROUND  = GND
  AC40  VSS(896)  GROUND  = GND
  AC42  DDR012_RCOMP(2)  BI  = A_CPU0_ABC_RCOMP2
  AC46  DDR2_MA(17)  OUT  = M_C_MA<17>
  AC48  VSS(733)  GROUND  = GND
  AC50  VSS(767)  GROUND  = GND
  AC52  VSS(858)  GROUND  = GND
  AC54  VSS(869)  GROUND  = GND
  AC56  VSS(964)  GROUND  = GND
  AC58  VSS(1186)  GROUND  = GND
  AC60  VSS(1187)  GROUND  = GND
  AC62  VSS(1188)  GROUND  = GND
  AC64  VSS(895)  GROUND  = GND
  AC66  DDR0_ECC(6)  BI  = M_A_ECC<6>
  AC68  DDR0_ECC(0)  BI  = M_A_ECC<0>
  AC70  VSS(894)  GROUND  = GND
  AC72  VSS(893)  GROUND  = GND
  AC74  DDR2_DQ(9)  BI  = M_C_DQ<9>
  AC76  DDR2_DQS_DP(10)  BI  = M_C_DQS_DP<10>
  AC78  VSS(892)  GROUND  = GND
  AC80  DDR1_DQ(15)  BI  = M_B_DQ<15>
  AC82  DDR1_DQ(10)  BI  = M_B_DQ<10>
  AC84  VSS(891)  GROUND  = GND
  AC86  VSS(890)  GROUND  = GND
  AD1  UPI0_TX_DP(5)  OUT  = UPI_CPU0_CPU1_P0P0_DP<14>
  AD3  VSS(889)  GROUND  = GND
  AD5  UPI0_RX_DN(3)  IN  = UPI_CPU1_CPU0_P0P0_DN<16>
  AD7  VSS(888)  GROUND  = GND
  AD9  VSS(887)  GROUND  = GND
  AD11  VSS(886)  GROUND  = GND
  AD13  VSS(885)  GROUND  = GND
  AD15  VSS(884)  GROUND  = GND
  AD17  DDR345_SPDSDA  BI  = SMB_DDR_DEF_SDA_G_R
  AD19  VSS(883)  GROUND  = GND
  AD21  VSS(882)  GROUND  = GND
  AD23  DDR2_DQ(62)  BI  = M_C_DQ<62>
  AD25  DDR2_DQ(56)  BI  = M_C_DQ<56>
  AD27  VSS(881)  GROUND  = GND
  AD29  DDR2_DQ(54)  BI  = M_C_DQ<54>
  AD31  DDR2_DQ(48)  BI  = M_C_DQ<48>
  AD33  VSS(880)  GROUND  = GND
  AD35  VCCIO(99)  POWER  = PVCCIO_CPU0
  AD37  VCCIO(96)  POWER  = PVCCIO_CPU0
  AD39  VSS(879)  GROUND  = GND
  AD41  VSENSEPMAX  POWER  = VSENSE_PMAX_CPU0
  AD43  VSS(878)  GROUND  = GND
  AD45  VCCD012(43)  POWER  = PVDDQ_ABC
  AD47  RSVD(254)  BI  = TP_CPU0_RSVD_254
  AD49  RSVD(253)  BI  = TP_CPU0_RSVD_253
  AD51  RSVD(252)  BI  = TP_CPU0_RSVD_252
  AD53  DDR2_MA(13)  OUT  = M_C_MA<13>
  AD55  DDR2_MA(10)  OUT  = M_C_MA<10>
  AD57  DDR2_MA(2)  OUT  = M_C_MA<2>
  AD59  DDR2_MA(8)  OUT  = M_C_MA<8>
  AD61  DDR2_ALERT_N  IN  = M_C_ALERT_N
  AD63  DDR2_CKE(1)  OUT  = M_C_CKE<1>
  AD65  DDR0_ECC(2)  BI  = M_A_ECC<2>
  AD67  DDR0_DQS_DP(17)  BI  = M_A_DQS_DP<17>
  AD69  DDR0_ECC(4)  BI  = M_A_ECC<4>
  AD71  VSS(877)  GROUND  = GND
  AD73  VSS(876)  GROUND  = GND
  AD75  VSS(875)  GROUND  = GND
  AD77  DDR2_DQS_DN(10)  BI  = M_C_DQS_DN<10>
  AD79  DDR1_DQS_DN(1)  BI  = M_B_DQS_DN<1>
  AD81  VSS(874)  GROUND  = GND
  AD83  VSS(873)  GROUND  = GND
  AD85  VSS(872)  GROUND  = GND
  AE2  UPI0_TX_DN(7)  OUT  = UPI_CPU0_CPU1_P0P0_DN<12>
  AE4  VSS(871)  GROUND  = GND
  AE6  UPI0_RX_DN(4)  IN  = UPI_CPU1_CPU0_P0P0_DN<15>
  AE8  VSS(870)  GROUND  = GND
  AE10  VCCIO(1)  POWER  = PVCCIO_CPU0
  AE12  BPM_N(6)  BI  = XDP_CPU_OBSFN_B0_MBP6_N
  AE14  TDO  OUT  = XDP_CPU0_TDO
  AE16  VSS(868)  GROUND  = GND
  AE18  DDR345_SPDSCL  BI  = SMB_DDR_DEF_SCL_G_R
  AE20  LEGACY_SKT  IN  = PU_CPU0_LEGACY_SKT
  AE22  DDR2_DQ(58)  BI  = M_C_DQ<58>
  AE24  DDR2_DQS_DP(16)  BI  = M_C_DQS_DP<16>
  AE26  DDR2_DQ(60)  BI  = M_C_DQ<60>
  AE28  DDR2_DQ(50)  BI  = M_C_DQ<50>
  AE30  DDR2_DQS_DP(15)  BI  = M_C_DQS_DP<15>
  AE32  DDR2_DQ(52)  BI  = M_C_DQ<52>
  AE34  VCCIO(100)  POWER  = PVCCIO_CPU0
  AE36  VCCIO(95)  POWER  = PVCCIO_CPU0
  AE38  VSS(867)  GROUND  = GND
  AE40  VSS(866)  GROUND  = GND
  AE42  VSS(865)  GROUND  = GND
  AE46  RSVD(251)  BI  = TP_CPU0_RSVD_251
  AE48  RSVD(250)  BI  = TP_CPU0_RSVD_250
  AE50  RSVD(249)  BI  = TP_CPU0_RSVD_249
  AE52  RSVD(248)  BI  = TP_CPU0_RSVD_248
  AE54  DDR2_MA(15)  OUT  = M_C_MA<15>
  AE56  DDR2_BA(1)  OUT  = M_C_BA<1>
  AE58  DDR2_MA(1)  OUT  = M_C_MA<1>
  AE60  DDR2_MA(7)  OUT  = M_C_MA<7>
  AE62  DDR2_BG(1)  OUT  = M_C_BG<1>
  AE64  VSS(864)  GROUND  = GND
  AE66  VSS(863)  GROUND  = GND
  AE68  VSS(862)  GROUND  = GND
  AE70  VSS(861)  GROUND  = GND
  AE72  RSVD(247)  BI  = TP_CPU0_RSVD_247
  AE74  DDR2_DQ(13)  BI  = M_C_DQ<13>
  AE76  DDR2_DQ(8)  BI  = M_C_DQ<8>
  AE78  VSS(860)  GROUND  = GND
  AE80  DDR1_DQS_DP(1)  BI  = M_B_DQS_DP<1>
  AE82  DDR1_DQ(14)  BI  = M_B_DQ<14>
  AE84  DDR0_DQ(3)  BI  = M_A_DQ<3>
  AE86  DDR0_DQ(2)  BI  = M_A_DQ<2>
  AF1  VSS(859)  GROUND  = GND
  AF3  UPI0_TX_DP(6)  OUT  = UPI_CPU0_CPU1_P0P0_DP<13>
  AF5  VCCIO(2)  POWER  = PVCCIO_CPU0
  AF7  UPI0_RX_DP(5)  IN  = UPI_CPU1_CPU0_P0P0_DP<14>
  AF9  VSS(857)  GROUND  = GND
  AF11  BPM_N(3)  BI  = TP_XDP_CPU0_OBSDATA_A1_MBP3_N
  AF13  MEM_HOT_C345_N  BI  = H_CPU0_MEMDEF_MEMHOT_G_N
  AF15  PM_FAST_WAKE_N  BI  = H_CPU0_FAST_WAKE_N
  AF17  DDR012_SPDSDA  BI  = SMB_DDR_ABC_SDA_G_R
  AF19  RSVD(246)  BI  = TP_CPU0_RSVD_246
  AF21  VSS(856)  GROUND  = GND
  AF23  VSS(855)  GROUND  = GND
  AF25  VSS(854)  GROUND  = GND
  AF27  VSS(853)  GROUND  = GND
  AF29  VSS(852)  GROUND  = GND
  AF31  VSS(851)  GROUND  = GND
  AF33  VSS(850)  GROUND  = GND
  AF35  VCCIO(98)  POWER  = PVCCIO_CPU0
  AF37  VSS(849)  GROUND  = GND
  AF39  VSS(848)  GROUND  = GND
  AF41  VSS(847)  GROUND  = GND
  AF43  VCCIN(267)  POWER  = PVCCIN_CPU0
  AF45  TEST_1  BI  = PD_CPU0_RSVD_TEST_1
  AF47  RSVD(245)  BI  = TP_CPU0_RSVD_245
  AF49  RSVD(244)  BI  = TP_CPU0_RSVD_244
  AF51  RSVD(243)  BI  = TP_CPU0_RSVD_243
  AF53  RSVD(242)  BI  = TP_CPU0_RSVD_242
  AF55  VCCD012(44)  POWER  = PVDDQ_ABC
  AF57  VCCD012(45)  POWER  = PVDDQ_ABC
  AF59  VCCD012(46)  POWER  = PVDDQ_ABC
  AF61  VCCD012(47)  POWER  = PVDDQ_ABC
  AF63  VCCD012(48)  POWER  = PVDDQ_ABC
  AF65  DDR0_ECC(3)  BI  = M_A_ECC<3>
  AF67  DDR0_DQS_DP(8)  BI  = M_A_DQS_DP<8>
  AF69  DDR0_ECC(5)  BI  = M_A_ECC<5>
  AF71  RSVD(241)  BI  = TP_CPU0_RSVD_241
  AF73  VSS(846)  GROUND  = GND
  AF75  DDR2_DQ(12)  BI  = M_C_DQ<12>
  AF77  VSS(845)  GROUND  = GND
  AF79  DDR1_DQ(9)  BI  = M_B_DQ<9>
  AF81  DDR1_DQS_DP(10)  BI  = M_B_DQS_DP<10>
  AF83  VSS(844)  GROUND  = GND
  AF85  VSS(843)  GROUND  = GND
  AG2  UPI0_TX_DP(7)  OUT  = UPI_CPU0_CPU1_P0P0_DP<12>
  AG4  UPI0_TX_DN(6)  OUT  = UPI_CPU0_CPU1_P0P0_DN<13>
  AG6  UPI0_RX_DP(4)  IN  = UPI_CPU1_CPU0_P0P0_DP<15>
  AG8  UPI0_RX_DN(5)  IN  = UPI_CPU1_CPU0_P0P0_DN<14>
  AG10  BPM_N(2)  BI  = TP_XDP_CPU0_OBSDATA_A0_MBP2_N
  AG12  VSS(842)  GROUND  = GND
  AG14  VSS(841)  GROUND  = GND
  AG16  PRDY_N  OUT  = XDP_CPU_PRDY_N
  AG18  VSS(840)  GROUND  = GND
  AG20  RSVD(240)  BI  = TP_CPU0_RSVD_240
  AG22  DDR2_DQ(59)  BI  = M_C_DQ<59>
  AG24  DDR2_DQS_DP(7)  BI  = M_C_DQS_DP<7>
  AG26  DDR2_DQ(61)  BI  = M_C_DQ<61>
  AG28  DDR2_DQ(51)  BI  = M_C_DQ<51>
  AG30  DDR2_DQS_DP(6)  BI  = M_C_DQS_DP<6>
  AG32  DDR2_DQ(53)  BI  = M_C_DQ<53>
  AG34  VCCIO(101)  POWER  = PVCCIO_CPU0
  AG36  VSS(839)  GROUND  = GND
  AG38  VCCIN(266)  POWER  = PVCCIN_CPU0
  AG40  VCCIN(265)  POWER  = PVCCIN_CPU0
  AG42  VCCIN(264)  POWER  = PVCCIN_CPU0
  AG46  TEST_2  BI  = PD_CPU0_RSVD_TEST_2
  AG48  RSVD(239)  BI  = TP_CPU0_RSVD_239
  AG50  RSVD(238)  BI  = TP_CPU0_RSVD_238
  AG52  RSVD(237)  BI  = TP_CPU0_RSVD_237
  AG54  RSVD(236)  BI  = TP_CPU0_RSVD_236
  AG56  RSVD(235)  BI  = TP_CPU0_RSVD_235
  AG58  DDR2_MA(9)  OUT  = M_C_MA<9>
  AG60  DDR2_MA(11)  OUT  = M_C_MA<11>
  AG62  DDR2_MA(12)  OUT  = M_C_MA<12>
  AG64  VSS(838)  GROUND  = GND
  AG66  DDR0_ECC(7)  BI  = M_A_ECC<7>
  AG68  DDR0_ECC(1)  BI  = M_A_ECC<1>
  AG70  VSS(837)  GROUND  = GND
  AG72  RSVD(234)  BI  = TP_CPU0_RSVD_234
  AG74  VSS(836)  GROUND  = GND
  AG76  VSS(835)  GROUND  = GND
  AG78  VSS(834)  GROUND  = GND
  AG80  VSS(833)  GROUND  = GND
  AG82  DDR1_DQS_DN(10)  BI  = M_B_DQS_DN<10>
  AG84  DDR0_DQ(7)  BI  = M_A_DQ<7>
  AG86  DDR0_DQ(6)  BI  = M_A_DQ<6>
  AH1  VSS(832)  GROUND  = GND
  AH3  UPI0_TX_DN(8)  OUT  = UPI_CPU0_CPU1_P0P0_DN<11>
  AH5  VSS(831)  GROUND  = GND
  AH7  UPI0_RX_DP(6)  IN  = UPI_CPU1_CPU0_P0P0_DP<13>
  AH9  VCCIO(42)  POWER  = PVCCIO_CPU0
  AH11  BPM_N(1)  BI  = XDP_CPU_MBP1_N
  AH13  MEM_HOT_C012_N  BI  = H_CPU0_MEMABC_MEMHOT_G_N
  AH15  RSVD(233)  BI  = TP_CPU0_RSVD_233
  AH19  RSVD(232)  BI  = TP_CPU0_RSVD_232
  AH21  VSS(830)  GROUND  = GND
  AH23  DDR2_DQ(63)  BI  = M_C_DQ<63>
  AH25  DDR2_DQ(57)  BI  = M_C_DQ<57>
  AH27  VSS(829)  GROUND  = GND
  AH29  DDR2_DQ(55)  BI  = M_C_DQ<55>
  AH31  DDR2_DQ(49)  BI  = M_C_DQ<49>
  AH33  VSS(828)  GROUND  = GND
  AH35  VSS(827)  GROUND  = GND
  AH37  VCCIN(263)  POWER  = PVCCIN_CPU0
  AH39  VCCIN(262)  POWER  = PVCCIN_CPU0
  AH41  VCCIN(261)  POWER  = PVCCIN_CPU0
  AH45  VSS(826)  GROUND  = GND
  AH47  VSS(825)  GROUND  = GND
  AH49  VSS(824)  GROUND  = GND
  AH51  VSS(823)  GROUND  = GND
  AH53  VSS(822)  GROUND  = GND
